(kicad_pcb
	(version 20260206)
	(generator "pcbnew")
	(generator_version "10.0")
	(general
		(thickness 1.6)
		(legacy_teardrops no)
	)
	(paper "A4")
	(title_block
		(title "Wiwynn_Tioga_Pass_MB.brd")
		(comment 1 "Tioga Pass / footprint 190 of 4770 (U2D1), pads 1965-2073 of 3647")
	)
	(layers
		(0 "F.Cu" signal "TOP")
		(4 "In1.Cu" signal "L2GND")
		(6 "In2.Cu" signal "L3")
		(8 "In3.Cu" signal "L4GND")
		(10 "In4.Cu" signal "L5")
		(12 "In5.Cu" signal "L6GND")
		(14 "In6.Cu" signal "L7VCC")
		(16 "In7.Cu" signal "L8VCC")
		(18 "In8.Cu" signal "L9GND")
		(20 "In9.Cu" signal "L10")
		(22 "In10.Cu" signal "L11GND")
		(24 "In11.Cu" signal "L12")
		(26 "In12.Cu" signal "L13GND")
		(2 "B.Cu" signal "BOTTOM")
		(9 "F.Adhes" user "F.Adhesive")
		(11 "B.Adhes" user "B.Adhesive")
		(13 "F.Paste" user "Package Geometry/Pastemask Top")
		(15 "B.Paste" user "Package Geometry/Pastemask Bottom")
		(5 "F.SilkS" user "Ref Des/Silkscreen Top")
		(7 "B.SilkS" user "Ref Des/Silkscreen Bottom")
		(1 "F.Mask" user "Board Geometry/Soldermask Top")
		(3 "B.Mask" user "Board Geometry/Soldermask Bottom")
		(17 "Dwgs.User" user "User.Drawings")
		(19 "Cmts.User" user "User.Comments")
		(21 "Eco1.User" user "User.Eco1")
		(23 "Eco2.User" user "User.Eco2")
		(25 "Edge.Cuts" user "Board Geometry/Outline")
		(27 "Margin" user)
		(31 "F.CrtYd" user "Package Geometry/Place Bound Top")
		(29 "B.CrtYd" user "Package Geometry/Place Bound Bottom")
		(35 "F.Fab" user "Ref Des/Assembly Top")
		(33 "B.Fab" user "Ref Des/Assembly Bottom")
	)
	(footprint ""
		(layer "F.Cu")
		(at 104.99979 -76.550012 180)
		(property "Reference" "U2D1"
			(at 25.19299 30.484318 0)
			(unlocked yes)
			(layer "F.SilkS")
			(effects
				(font
					(size 0.7874 0.5842)
					(thickness 0.1524)
				)
			)
		)
		(property "Value" ""
			(at 0 0 180)
			(layer "F.Fab")
			(effects
				(font
					(size 1.27 1.27)
				)
			)
		)
		(duplicate_pad_numbers_are_jumpers no)
		(pad "DA50" smd circle
			(at 6.344412 12.720828)
			(size 0.4318 0.4318)
			(layers "F.Cu" "F.Mask" "F.Paste")
			(net "GND")
		)
		(pad "DA52" smd circle
			(at 8.061452 12.720828)
			(size 0.4318 0.4318)
			(layers "F.Cu" "F.Mask" "F.Paste")
			(net "TP_CPU1_RSVD_50")
		)
		(pad "DA54" smd circle
			(at 9.778492 12.720828)
			(size 0.4318 0.4318)
			(layers "F.Cu" "F.Mask" "F.Paste")
			(net "TP_CPU1_RSVD_49")
		)
		(pad "DA56" smd circle
			(at 11.495532 12.720828)
			(size 0.4318 0.4318)
			(layers "F.Cu" "F.Mask" "F.Paste")
			(net "TP_CPU1_RSVD_48")
		)
		(pad "DA58" smd circle
			(at 13.212572 12.720828)
			(size 0.4318 0.4318)
			(layers "F.Cu" "F.Mask" "F.Paste")
			(net "M_M_MA<9>")
		)
		(pad "DA60" smd circle
			(at 14.929612 12.720828)
			(size 0.4318 0.4318)
			(layers "F.Cu" "F.Mask" "F.Paste")
			(net "M_M_MA<11>")
		)
		(pad "DA62" smd circle
			(at 16.646398 12.720828)
			(size 0.4318 0.4318)
			(layers "F.Cu" "F.Mask" "F.Paste")
			(net "M_M_BG<0>")
		)
		(pad "DA64" smd circle
			(at 18.363438 12.720828)
			(size 0.4318 0.4318)
			(layers "F.Cu" "F.Mask" "F.Paste")
			(net "GND")
		)
		(pad "DA66" smd circle
			(at 20.080478 12.720828)
			(size 0.4318 0.4318)
			(layers "F.Cu" "F.Mask" "F.Paste")
			(net "M_K_ECC<6>")
		)
		(pad "DA68" smd circle
			(at 21.797518 12.720828)
			(size 0.4318 0.4318)
			(layers "F.Cu" "F.Mask" "F.Paste")
			(net "M_K_ECC<0>")
		)
		(pad "DA70" smd circle
			(at 23.514558 12.720828)
			(size 0.4318 0.4318)
			(layers "F.Cu" "F.Mask" "F.Paste")
			(net "GND")
		)
		(pad "DA72" smd circle
			(at 25.231598 12.720828)
			(size 0.4318 0.4318)
			(layers "F.Cu" "F.Mask" "F.Paste")
			(net "FM_CPU1_PKGID2")
		)
		(pad "DA74" smd circle
			(at 26.948384 12.720828)
			(size 0.4318 0.4318)
			(layers "F.Cu" "F.Mask" "F.Paste")
			(net "GND")
		)
		(pad "DA76" smd circle
			(at 28.665424 12.720828)
			(size 0.4318 0.4318)
			(layers "F.Cu" "F.Mask" "F.Paste")
			(net "GND")
		)
		(pad "DA78" smd circle
			(at 30.382464 12.720828)
			(size 0.4318 0.4318)
			(layers "F.Cu" "F.Mask" "F.Paste")
			(net "GND")
		)
		(pad "DA80" smd circle
			(at 32.099504 12.720828)
			(size 0.4318 0.4318)
			(layers "F.Cu" "F.Mask" "F.Paste")
			(net "GND")
		)
		(pad "DA82" smd circle
			(at 33.816544 12.720828)
			(size 0.4318 0.4318)
			(layers "F.Cu" "F.Mask" "F.Paste")
			(net "M_L_DQS_DN<1>")
		)
		(pad "DA84" smd circle
			(at 35.533584 12.720828)
			(size 0.4318 0.4318)
			(layers "F.Cu" "F.Mask" "F.Paste")
			(net "M_K_DQ<3>")
		)
		(pad "DA86" smd custom
			(at 37.250624 12.720828 270)
			(size 0.10795 0.10795)
			(layers "F.Cu" "F.Mask" "F.Paste")
			(net "M_K_DQ<2>")
			(options
				(clearance outline)
				(anchor circle)
			)
			(primitives
				(gr_poly
					(pts
						(arc
							(start 0.2159 -0.0381)
							(mid 0 -0.254)
							(end -0.2159 -0.0381)
						)
						(arc
							(start -0.2159 0.0381)
							(mid 0 0.254)
							(end 0.2159 0.0381)
						)
					)
					(width 0)
					(fill yes)
				)
			)
		)
		(pad "DB1" smd custom
			(at -37.250624 15.015972 90)
			(size 0.10795 0.10795)
			(layers "F.Cu" "F.Mask" "F.Paste")
			(net "TP_P3E_CPU1_PE1_MP_TXP<1>")
			(options
				(clearance outline)
				(anchor circle)
			)
			(primitives
				(gr_poly
					(pts
						(arc
							(start 0.2159 -0.0381)
							(mid 0 -0.254)
							(end -0.2159 -0.0381)
						)
						(arc
							(start -0.2159 0.0381)
							(mid 0 0.254)
							(end 0.2159 0.0381)
						)
					)
					(width 0)
					(fill yes)
				)
			)
		)
		(pad "DB3" smd circle
			(at -35.533584 15.015972)
			(size 0.4318 0.4318)
			(layers "F.Cu" "F.Mask" "F.Paste")
			(net "GND")
		)
		(pad "DB5" smd circle
			(at -33.816544 15.015972)
			(size 0.4318 0.4318)
			(layers "F.Cu" "F.Mask" "F.Paste")
			(net "P3E_CPU1_PE3_MP_TXN<14>")
		)
		(pad "DB7" smd circle
			(at -32.099504 15.015972)
			(size 0.4318 0.4318)
			(layers "F.Cu" "F.Mask" "F.Paste")
			(net "GND")
		)
		(pad "DB9" smd circle
			(at -30.382464 15.015972)
			(size 0.4318 0.4318)
			(layers "F.Cu" "F.Mask" "F.Paste")
			(net "TP_P3E_CPU1_PE1_MP_RXP<2>")
		)
		(pad "DB11" smd circle
			(at -28.665424 15.015972)
			(size 0.4318 0.4318)
			(layers "F.Cu" "F.Mask" "F.Paste")
			(net "P3E_CPU1_PE3_MP_RXN<13>")
		)
		(pad "DB13" smd circle
			(at -26.948384 15.015972)
			(size 0.4318 0.4318)
			(layers "F.Cu" "F.Mask" "F.Paste")
			(net "GND")
		)
		(pad "DB15" smd circle
			(at -25.231598 15.015972)
			(size 0.4318 0.4318)
			(layers "F.Cu" "F.Mask" "F.Paste")
			(net "TP_CPU1_UPI2_RSVD_CW16")
		)
		(pad "DB17" smd circle
			(at -23.514558 15.015972)
			(size 0.4318 0.4318)
			(layers "F.Cu" "F.Mask" "F.Paste")
			(net "GND")
		)
		(pad "DB19" smd circle
			(at -21.797518 15.015972)
			(size 0.4318 0.4318)
			(layers "F.Cu" "F.Mask" "F.Paste")
			(net "GND")
		)
		(pad "DB21" smd circle
			(at -20.080478 15.015972)
			(size 0.4318 0.4318)
			(layers "F.Cu" "F.Mask" "F.Paste")
			(net "GND")
		)
		(pad "DB23" smd circle
			(at -18.363438 15.015972)
			(size 0.4318 0.4318)
			(layers "F.Cu" "F.Mask" "F.Paste")
			(net "GND")
		)
		(pad "DB25" smd circle
			(at -16.646398 15.015972)
			(size 0.4318 0.4318)
			(layers "F.Cu" "F.Mask" "F.Paste")
			(net "GND")
		)
		(pad "DB27" smd circle
			(at -14.929612 15.015972)
			(size 0.4318 0.4318)
			(layers "F.Cu" "F.Mask" "F.Paste")
			(net "M_M_DQ<59>")
		)
		(pad "DB29" smd circle
			(at -13.212572 15.015972)
			(size 0.4318 0.4318)
			(layers "F.Cu" "F.Mask" "F.Paste")
			(net "M_M_DQS_DP<7>")
		)
		(pad "DB31" smd circle
			(at -11.495532 15.015972)
			(size 0.4318 0.4318)
			(layers "F.Cu" "F.Mask" "F.Paste")
			(net "M_M_DQ<61>")
		)
		(pad "DB33" smd circle
			(at -9.778492 15.015972)
			(size 0.4318 0.4318)
			(layers "F.Cu" "F.Mask" "F.Paste")
			(net "M_M_DQ<51>")
		)
		(pad "DB35" smd circle
			(at -8.061452 15.015972)
			(size 0.4318 0.4318)
			(layers "F.Cu" "F.Mask" "F.Paste")
			(net "M_M_DQS_DP<6>")
		)
		(pad "DB37" smd circle
			(at -6.344412 15.015972)
			(size 0.4318 0.4318)
			(layers "F.Cu" "F.Mask" "F.Paste")
			(net "M_M_DQ<53>")
		)
		(pad "DB39" smd circle
			(at -4.627626 15.015972)
			(size 0.4318 0.4318)
			(layers "F.Cu" "F.Mask" "F.Paste")
			(net "GND")
		)
		(pad "DB41" smd circle
			(at -2.910586 15.015972)
			(size 0.4318 0.4318)
			(layers "F.Cu" "F.Mask" "F.Paste")
			(net "GND")
		)
		(pad "DB45" smd circle
			(at 2.052066 13.215874)
			(size 0.4318 0.4318)
			(layers "F.Cu" "F.Mask" "F.Paste")
			(net "SVID_DIO0_CPU1")
		)
		(pad "DB47" smd circle
			(at 3.769106 13.215874)
			(size 0.4318 0.4318)
			(layers "F.Cu" "F.Mask" "F.Paste")
			(net "GND")
		)
		(pad "DB49" smd circle
			(at 5.485892 13.215874)
			(size 0.4318 0.4318)
			(layers "F.Cu" "F.Mask" "F.Paste")
			(net "GND")
		)
		(pad "DB51" smd circle
			(at 7.202932 13.215874)
			(size 0.4318 0.4318)
			(layers "F.Cu" "F.Mask" "F.Paste")
			(net "PD_CPU1_TEST13")
		)
		(pad "DB53" smd circle
			(at 8.919972 13.215874)
			(size 0.4318 0.4318)
			(layers "F.Cu" "F.Mask" "F.Paste")
			(net "PVDDQ_KLM")
		)
		(pad "DB55" smd circle
			(at 10.637012 13.215874)
			(size 0.4318 0.4318)
			(layers "F.Cu" "F.Mask" "F.Paste")
			(net "PVDDQ_KLM")
		)
		(pad "DB57" smd circle
			(at 12.354052 13.215874)
			(size 0.4318 0.4318)
			(layers "F.Cu" "F.Mask" "F.Paste")
			(net "PVDDQ_KLM")
		)
		(pad "DB59" smd circle
			(at 14.071092 13.215874)
			(size 0.4318 0.4318)
			(layers "F.Cu" "F.Mask" "F.Paste")
			(net "PVDDQ_KLM")
		)
		(pad "DB61" smd circle
			(at 15.787878 13.215874)
			(size 0.4318 0.4318)
			(layers "F.Cu" "F.Mask" "F.Paste")
			(net "PVDDQ_KLM")
		)
		(pad "DB63" smd circle
			(at 17.504918 13.215874)
			(size 0.4318 0.4318)
			(layers "F.Cu" "F.Mask" "F.Paste")
			(net "PVDDQ_KLM")
		)
		(pad "DB65" smd circle
			(at 19.221958 13.215874)
			(size 0.4318 0.4318)
			(layers "F.Cu" "F.Mask" "F.Paste")
			(net "M_K_ECC<2>")
		)
		(pad "DB67" smd circle
			(at 20.938998 13.215874)
			(size 0.4318 0.4318)
			(layers "F.Cu" "F.Mask" "F.Paste")
			(net "M_K_DQS_DN<17>")
		)
		(pad "DB69" smd circle
			(at 22.656038 13.215874)
			(size 0.4318 0.4318)
			(layers "F.Cu" "F.Mask" "F.Paste")
			(net "M_K_ECC<4>")
		)
		(pad "DB71" smd circle
			(at 24.373078 13.215874)
			(size 0.4318 0.4318)
			(layers "F.Cu" "F.Mask" "F.Paste")
			(net "FM_CPU1_PROC_ID1")
		)
		(pad "DB73" smd circle
			(at 26.090118 13.215874)
			(size 0.4318 0.4318)
			(layers "F.Cu" "F.Mask" "F.Paste")
			(net "GND")
		)
		(pad "DB75" smd circle
			(at 27.806904 13.215874)
			(size 0.4318 0.4318)
			(layers "F.Cu" "F.Mask" "F.Paste")
			(net "M_M_DQ<13>")
		)
		(pad "DB77" smd circle
			(at 29.523944 13.215874)
			(size 0.4318 0.4318)
			(layers "F.Cu" "F.Mask" "F.Paste")
			(net "GND")
		)
		(pad "DB79" smd circle
			(at 31.240984 13.215874)
			(size 0.4318 0.4318)
			(layers "F.Cu" "F.Mask" "F.Paste")
			(net "M_L_DQ<8>")
		)
		(pad "DB81" smd circle
			(at 32.958024 13.215874)
			(size 0.4318 0.4318)
			(layers "F.Cu" "F.Mask" "F.Paste")
			(net "M_L_DQS_DP<1>")
		)
		(pad "DB83" smd circle
			(at 34.675064 13.215874)
			(size 0.4318 0.4318)
			(layers "F.Cu" "F.Mask" "F.Paste")
			(net "GND")
		)
		(pad "DB85" smd circle
			(at 36.392104 13.215874)
			(size 0.4318 0.4318)
			(layers "F.Cu" "F.Mask" "F.Paste")
			(net "GND")
		)
		(pad "DC2" smd custom
			(at -36.392104 15.511526 90)
			(size 0.10795 0.10795)
			(layers "F.Cu" "F.Mask" "F.Paste")
			(net "TP_P3E_CPU1_PE1_MP_TXN<1>")
			(options
				(clearance outline)
				(anchor circle)
			)
			(primitives
				(gr_poly
					(pts
						(arc
							(start 0.2159 -0.0381)
							(mid 0 -0.254)
							(end -0.2159 -0.0381)
						)
						(arc
							(start -0.2159 0.0381)
							(mid 0 0.254)
							(end 0.2159 0.0381)
						)
					)
					(width 0)
					(fill yes)
				)
			)
		)
		(pad "DC4" smd circle
			(at -34.675064 15.511526)
			(size 0.4318 0.4318)
			(layers "F.Cu" "F.Mask" "F.Paste")
			(net "TP_P3E_CPU1_PE1_MP_TXP<3>")
		)
		(pad "DC6" smd circle
			(at -32.958024 15.511526)
			(size 0.4318 0.4318)
			(layers "F.Cu" "F.Mask" "F.Paste")
			(net "P3E_CPU1_PE3_MP_TXP<13>")
		)
		(pad "DC8" smd circle
			(at -31.240984 15.511526)
			(size 0.4318 0.4318)
			(layers "F.Cu" "F.Mask" "F.Paste")
			(net "TP_P3E_CPU1_PE1_MP_RXN<2>")
		)
		(pad "DC10" smd circle
			(at -29.523944 15.511526)
			(size 0.4318 0.4318)
			(layers "F.Cu" "F.Mask" "F.Paste")
			(net "TP_P3E_CPU1_PE1_MP_RXN<3>")
		)
		(pad "DC12" smd circle
			(at -27.806904 15.511526)
			(size 0.4318 0.4318)
			(layers "F.Cu" "F.Mask" "F.Paste")
			(net "P3E_CPU1_PE3_MP_RXN<12>")
		)
		(pad "DC14" smd circle
			(at -26.090118 15.511526)
			(size 0.4318 0.4318)
			(layers "F.Cu" "F.Mask" "F.Paste")
			(net "GND")
		)
		(pad "DC16" smd circle
			(at -24.373078 15.511526)
			(size 0.4318 0.4318)
			(layers "F.Cu" "F.Mask" "F.Paste")
			(net "TP_CPU1_UPI2_RSVD_DA16")
		)
		(pad "DC18" smd circle
			(at -22.656038 15.511526)
			(size 0.4318 0.4318)
			(layers "F.Cu" "F.Mask" "F.Paste")
			(net "PVCCIO_CPU1")
		)
		(pad "DC20" smd circle
			(at -20.938998 15.511526)
			(size 0.4318 0.4318)
			(layers "F.Cu" "F.Mask" "F.Paste")
			(net "GND")
		)
		(pad "DC22" smd circle
			(at -19.221958 15.511526)
			(size 0.4318 0.4318)
			(layers "F.Cu" "F.Mask" "F.Paste")
			(net "GND")
		)
		(pad "DC24" smd circle
			(at -17.504918 15.511526)
			(size 0.4318 0.4318)
			(layers "F.Cu" "F.Mask" "F.Paste")
			(net "GND")
		)
		(pad "DC26" smd circle
			(at -15.787878 15.511526)
			(size 0.4318 0.4318)
			(layers "F.Cu" "F.Mask" "F.Paste")
			(net "GND")
		)
		(pad "DC28" smd circle
			(at -14.071092 15.511526)
			(size 0.4318 0.4318)
			(layers "F.Cu" "F.Mask" "F.Paste")
			(net "M_M_DQ<63>")
		)
		(pad "DC30" smd circle
			(at -12.354052 15.511526)
			(size 0.4318 0.4318)
			(layers "F.Cu" "F.Mask" "F.Paste")
			(net "M_M_DQ<57>")
		)
		(pad "DC32" smd circle
			(at -10.637012 15.511526)
			(size 0.4318 0.4318)
			(layers "F.Cu" "F.Mask" "F.Paste")
			(net "GND")
		)
		(pad "DC34" smd circle
			(at -8.919972 15.511526)
			(size 0.4318 0.4318)
			(layers "F.Cu" "F.Mask" "F.Paste")
			(net "M_M_DQ<55>")
		)
		(pad "DC36" smd circle
			(at -7.202932 15.511526)
			(size 0.4318 0.4318)
			(layers "F.Cu" "F.Mask" "F.Paste")
			(net "M_M_DQ<49>")
		)
		(pad "DC38" smd circle
			(at -5.485892 15.511526)
			(size 0.4318 0.4318)
			(layers "F.Cu" "F.Mask" "F.Paste")
			(net "GND")
		)
		(pad "DC40" smd circle
			(at -3.769106 15.511526)
			(size 0.4318 0.4318)
			(layers "F.Cu" "F.Mask" "F.Paste")
			(net "M_M_DQS_DP<13>")
		)
		(pad "DC42" smd circle
			(at -2.052066 15.511526)
			(size 0.4318 0.4318)
			(layers "F.Cu" "F.Mask" "F.Paste")
			(net "GND")
		)
		(pad "DC44" smd circle
			(at 1.193546 13.711428)
			(size 0.508 0.508)
			(layers "F.Cu" "F.Mask" "F.Paste")
			(net "SVID_CLK0_CPU1")
		)
		(pad "DC46" smd circle
			(at 2.910586 13.711428)
			(size 0.4318 0.4318)
			(layers "F.Cu" "F.Mask" "F.Paste")
			(net "TP_CPU1_RSVD_47")
		)
		(pad "DC48" smd circle
			(at 4.627626 13.711428)
			(size 0.4318 0.4318)
			(layers "F.Cu" "F.Mask" "F.Paste")
			(net "A_CPU1_KLM_RCOMP0")
		)
		(pad "DC50" smd circle
			(at 6.344412 13.711428)
			(size 0.4318 0.4318)
			(layers "F.Cu" "F.Mask" "F.Paste")
			(net "PD_CPU1_TEST14")
		)
		(pad "DC52" smd circle
			(at 8.061452 13.711428)
			(size 0.4318 0.4318)
			(layers "F.Cu" "F.Mask" "F.Paste")
			(net "TP_CPU1_RSVD_46")
		)
		(pad "DC54" smd circle
			(at 9.778492 13.711428)
			(size 0.4318 0.4318)
			(layers "F.Cu" "F.Mask" "F.Paste")
			(net "M_M_MA<15>")
		)
		(pad "DC56" smd circle
			(at 11.495532 13.711428)
			(size 0.4318 0.4318)
			(layers "F.Cu" "F.Mask" "F.Paste")
			(net "M_M_BA<1>")
		)
		(pad "DC58" smd circle
			(at 13.212572 13.711428)
			(size 0.4318 0.4318)
			(layers "F.Cu" "F.Mask" "F.Paste")
			(net "M_M_MA<1>")
		)
		(pad "DC60" smd circle
			(at 14.929612 13.711428)
			(size 0.4318 0.4318)
			(layers "F.Cu" "F.Mask" "F.Paste")
			(net "M_M_MA<7>")
		)
		(pad "DC62" smd circle
			(at 16.646398 13.711428)
			(size 0.4318 0.4318)
			(layers "F.Cu" "F.Mask" "F.Paste")
			(net "M_M_ACT_N")
		)
		(pad "DC64" smd circle
			(at 18.363438 13.711428)
			(size 0.4318 0.4318)
			(layers "F.Cu" "F.Mask" "F.Paste")
			(net "GND")
		)
		(pad "DC66" smd circle
			(at 20.080478 13.711428)
			(size 0.4318 0.4318)
			(layers "F.Cu" "F.Mask" "F.Paste")
			(net "GND")
		)
		(pad "DC68" smd circle
			(at 21.797518 13.711428)
			(size 0.4318 0.4318)
			(layers "F.Cu" "F.Mask" "F.Paste")
			(net "GND")
		)
		(pad "DC70" smd circle
			(at 23.514558 13.711428)
			(size 0.4318 0.4318)
			(layers "F.Cu" "F.Mask" "F.Paste")
			(net "GND")
		)
		(pad "DC72" smd circle
			(at 25.231598 13.711428)
			(size 0.4318 0.4318)
			(layers "F.Cu" "F.Mask" "F.Paste")
			(net "FM_CPU1_PKGID0")
		)
		(pad "DC74" smd circle
			(at 26.948384 13.711428)
			(size 0.4318 0.4318)
			(layers "F.Cu" "F.Mask" "F.Paste")
			(net "M_M_DQ<12>")
		)
		(pad "DC76" smd circle
			(at 28.665424 13.711428)
			(size 0.4318 0.4318)
			(layers "F.Cu" "F.Mask" "F.Paste")
			(net "M_M_DQ<9>")
		)
		(pad "DC78" smd circle
			(at 30.382464 13.711428)
			(size 0.4318 0.4318)
			(layers "F.Cu" "F.Mask" "F.Paste")
			(net "GND")
		)
		(pad "DC80" smd circle
			(at 32.099504 13.711428)
			(size 0.4318 0.4318)
			(layers "F.Cu" "F.Mask" "F.Paste")
			(net "M_L_DQS_DN<10>")
		)
		(pad "DC82" smd circle
			(at 33.816544 13.711428)
			(size 0.4318 0.4318)
			(layers "F.Cu" "F.Mask" "F.Paste")
			(net "M_L_DQ<14>")
		)
		(pad "DC84" smd circle
			(at 35.533584 13.711428)
			(size 0.4318 0.4318)
			(layers "F.Cu" "F.Mask" "F.Paste")
			(net "GND")
		)
		(pad "DC86" smd custom
			(at 37.250624 13.711428 270)
			(size 0.10795 0.10795)
			(layers "F.Cu" "F.Mask" "F.Paste")
			(net "GND")
			(options
				(clearance outline)
				(anchor circle)
			)
			(primitives
				(gr_poly
					(pts
						(arc
							(start 0.2159 -0.0381)
							(mid 0 -0.254)
							(end -0.2159 -0.0381)
						)
						(arc
							(start -0.2159 0.0381)
							(mid 0 0.254)
							(end 0.2159 0.0381)
						)
					)
					(width 0)
					(fill yes)
				)
			)
		)
		(pad "DD3" smd circle
			(at -35.533584 16.006572)
			(size 0.4318 0.4318)
			(layers "F.Cu" "F.Mask" "F.Paste")
			(net "TP_P3E_CPU1_PE1_MP_TXP<2>")
		)
		(pad "DD5" smd circle
			(at -33.816544 16.006572)
			(size 0.4318 0.4318)
			(layers "F.Cu" "F.Mask" "F.Paste")
			(net "P3E_CPU1_PE3_MP_TXN<13>")
		)
		(pad "DD7" smd circle
			(at -32.099504 16.006572)
			(size 0.4318 0.4318)
			(layers "F.Cu" "F.Mask" "F.Paste")
			(net "PVCCIO_CPU1")
		)
		(pad "DD9" smd circle
			(at -30.382464 16.006572)
			(size 0.4318 0.4318)
			(layers "F.Cu" "F.Mask" "F.Paste")
			(net "TP_P3E_CPU1_PE1_MP_RXP<4>")
		)
		(pad "DD11" smd circle
			(at -28.665424 16.006572)
			(size 0.4318 0.4318)
			(layers "F.Cu" "F.Mask" "F.Paste")
			(net "GND")
		)
	)
)
